# S9S_MB_2U (Grand Teton) — schematic netlist excerpt (pin names and nets, part order shuffled) for the footprints in the layout excerpt that follows; sources: Cadence DE-HDL packaged netlist, KiCad conversion of 03242023_DA0F0TMBIJ0_F0T_Motherboard_J_brd_V01_OCP.brd

R3670  Q_RES  1K 1% CHIP  pkg 0402LF  page 250 : A = ADC128_A0 ; B = GND
R3640  Q_RES  10K 1% CHIP  pkg 0402LF  page 208 : A = P3V3_AUX ; B = CK440Q_OE_3

(kicad_pcb
	(version 20260206)
	(generator "pcbnew")
	(generator_version "10.0")
	(general
		(thickness 1.6)
		(legacy_teardrops no)
	)
	(paper "A4")
	(title_block
		(title "03242023_DA0F0TMBIJ0_F0T_Motherboard_J_brd_V01_OCP.brd")
		(comment 1 "Grand Teton / footprints 3505-3506 of 6105")
	)
	(layers
		(0 "F.Cu" signal "TOP")
		(4 "In1.Cu" signal "GND")
		(6 "In2.Cu" signal "IN1")
		(8 "In3.Cu" signal "GND1")
		(10 "In4.Cu" signal "IN2")
		(12 "In5.Cu" signal "GND2")
		(14 "In6.Cu" signal "IN3")
		(16 "In7.Cu" signal "GND3")
		(18 "In8.Cu" signal "VCC")
		(20 "In9.Cu" signal "VCC1")
		(22 "In10.Cu" signal "GND4")
		(24 "In11.Cu" signal "IN4")
		(26 "In12.Cu" signal "GND5")
		(28 "In13.Cu" signal "IN5")
		(30 "In14.Cu" signal "GND6")
		(32 "In15.Cu" signal "IN6")
		(34 "In16.Cu" signal "GND7")
		(2 "B.Cu" signal "BOTTOM")
		(9 "F.Adhes" user "F.Adhesive")
		(11 "B.Adhes" user "B.Adhesive")
		(13 "F.Paste" user "Package Geometry/Pastemask Top")
		(15 "B.Paste" user "Package Geometry/Pastemask Bottom")
		(5 "F.SilkS" user "Ref Des/Silkscreen Top")
		(7 "B.SilkS" user "Ref Des/Silkscreen Bottom")
		(1 "F.Mask" user "Board Geometry/Soldermask Top")
		(3 "B.Mask" user "Board Geometry/Soldermask Bottom")
		(17 "Dwgs.User" user "User.Drawings")
		(19 "Cmts.User" user "User.Comments")
		(21 "Eco1.User" user "User.Eco1")
		(23 "Eco2.User" user "User.Eco2")
		(25 "Edge.Cuts" user "Board Geometry/Outline")
		(27 "Margin" user)
		(31 "F.CrtYd" user "Package Geometry/Place Bound Top")
		(29 "B.CrtYd" user "Package Geometry/Place Bound Bottom")
		(35 "F.Fab" user "Ref Des/Assembly Top")
		(33 "B.Fab" user "Ref Des/Assembly Bottom")
	)
	(footprint ""
		(layer "F.Cu")
		(at 22.809454 -107.777026 180)
		(property "Reference" "R3670"
			(at 0 0 180)
			(layer "F.SilkS")
			(hide yes)
			(effects
				(font
					(size 1.27 1.27)
				)
			)
		)
		(property "Value" ""
			(at 0 0 180)
			(layer "F.Fab")
			(effects
				(font
					(size 1.27 1.27)
				)
			)
		)
		(duplicate_pad_numbers_are_jumpers no)
		(fp_line
			(start 0.7874 0.4064)
			(end -0.7874 0.4064)
			(stroke
				(width 0.1524)
				(type default)
			)
			(layer "F.SilkS")
		)
		(fp_line
			(start 0.7874 -0.4064)
			(end 0.7874 0.4064)
			(stroke
				(width 0.1524)
				(type default)
			)
			(layer "F.SilkS")
		)
		(fp_line
			(start -0.7874 0.4064)
			(end -0.7874 -0.4064)
			(stroke
				(width 0.1524)
				(type default)
			)
			(layer "F.SilkS")
		)
		(fp_line
			(start -0.7874 -0.4064)
			(end 0.7874 -0.4064)
			(stroke
				(width 0.1524)
				(type default)
			)
			(layer "F.SilkS")
		)
		(fp_line
			(start 0.67945 0.3048)
			(end 0.120396 0.3048)
			(stroke
				(width 0.1)
				(type default)
			)
			(layer "F.Fab")
		)
		(fp_line
			(start 0.67945 -0.3048)
			(end 0.67945 0.3048)
			(stroke
				(width 0.1)
				(type default)
			)
			(layer "F.Fab")
		)
		(fp_line
			(start 0.12065 -0.2794)
			(end 0.12065 -0.3048)
			(stroke
				(width 0.1)
				(type default)
			)
			(layer "F.Fab")
		)
		(fp_line
			(start 0.12065 -0.3048)
			(end 0.67945 -0.3048)
			(stroke
				(width 0.1)
				(type default)
			)
			(layer "F.Fab")
		)
		(fp_line
			(start 0.120396 0.3048)
			(end 0.120396 0.2794)
			(stroke
				(width 0.1)
				(type default)
			)
			(layer "F.Fab")
		)
		(fp_line
			(start 0.120396 0.2794)
			(end -0.12065 0.2794)
			(stroke
				(width 0.1)
				(type default)
			)
			(layer "F.Fab")
		)
		(fp_line
			(start -0.12065 0.3048)
			(end -0.67945 0.3048)
			(stroke
				(width 0.1)
				(type default)
			)
			(layer "F.Fab")
		)
		(fp_line
			(start -0.12065 0.2794)
			(end -0.12065 0.3048)
			(stroke
				(width 0.1)
				(type default)
			)
			(layer "F.Fab")
		)
		(fp_line
			(start -0.12065 -0.2794)
			(end 0.12065 -0.2794)
			(stroke
				(width 0.1)
				(type default)
			)
			(layer "F.Fab")
		)
		(fp_line
			(start -0.12065 -0.305054)
			(end -0.12065 -0.2794)
			(stroke
				(width 0.1)
				(type default)
			)
			(layer "F.Fab")
		)
		(fp_line
			(start -0.67945 0.3048)
			(end -0.67945 -0.305054)
			(stroke
				(width 0.1)
				(type default)
			)
			(layer "F.Fab")
		)
		(fp_line
			(start -0.67945 -0.305054)
			(end -0.12065 -0.305054)
			(stroke
				(width 0.1)
				(type default)
			)
			(layer "F.Fab")
		)
		(pad "1" smd circle
			(at -0.40005 0 180)
			(size 0 0)
			(layers "F.Cu" "F.Mask" "F.Paste")
			(net "ADC128_A0")
		)
		(pad "2" smd circle
			(at 0.40005 0 180)
			(size 0 0)
			(layers "F.Cu" "F.Mask" "F.Paste")
			(net "GND")
		)
	)
	(footprint ""
		(layer "F.Cu")
		(at 258.18338 -92.258388 180)
		(property "Reference" "R3640"
			(at 0 0 180)
			(layer "F.SilkS")
			(hide yes)
			(effects
				(font
					(size 1.27 1.27)
				)
			)
		)
		(property "Value" ""
			(at 0 0 180)
			(layer "F.Fab")
			(effects
				(font
					(size 1.27 1.27)
				)
			)
		)
		(duplicate_pad_numbers_are_jumpers no)
		(fp_line
			(start 0.7874 0.4064)
			(end -0.7874 0.4064)
			(stroke
				(width 0.1524)
				(type default)
			)
			(layer "F.SilkS")
		)
		(fp_line
			(start 0.7874 -0.4064)
			(end 0.7874 0.4064)
			(stroke
				(width 0.1524)
				(type default)
			)
			(layer "F.SilkS")
		)
		(fp_line
			(start -0.7874 0.4064)
			(end -0.7874 -0.4064)
			(stroke
				(width 0.1524)
				(type default)
			)
			(layer "F.SilkS")
		)
		(fp_line
			(start -0.7874 -0.4064)
			(end 0.7874 -0.4064)
			(stroke
				(width 0.1524)
				(type default)
			)
			(layer "F.SilkS")
		)
		(fp_line
			(start 0.67945 0.3048)
			(end 0.120396 0.3048)
			(stroke
				(width 0.1)
				(type default)
			)
			(layer "F.Fab")
		)
		(fp_line
			(start 0.67945 -0.3048)
			(end 0.67945 0.3048)
			(stroke
				(width 0.1)
				(type default)
			)
			(layer "F.Fab")
		)
		(fp_line
			(start 0.12065 -0.2794)
			(end 0.12065 -0.3048)
			(stroke
				(width 0.1)
				(type default)
			)
			(layer "F.Fab")
		)
		(fp_line
			(start 0.12065 -0.3048)
			(end 0.67945 -0.3048)
			(stroke
				(width 0.1)
				(type default)
			)
			(layer "F.Fab")
		)
		(fp_line
			(start 0.120396 0.3048)
			(end 0.120396 0.2794)
			(stroke
				(width 0.1)
				(type default)
			)
			(layer "F.Fab")
		)
		(fp_line
			(start 0.120396 0.2794)
			(end -0.12065 0.2794)
			(stroke
				(width 0.1)
				(type default)
			)
			(layer "F.Fab")
		)
		(fp_line
			(start -0.12065 0.3048)
			(end -0.67945 0.3048)
			(stroke
				(width 0.1)
				(type default)
			)
			(layer "F.Fab")
		)
		(fp_line
			(start -0.12065 0.2794)
			(end -0.12065 0.3048)
			(stroke
				(width 0.1)
				(type default)
			)
			(layer "F.Fab")
		)
		(fp_line
			(start -0.12065 -0.2794)
			(end 0.12065 -0.2794)
			(stroke
				(width 0.1)
				(type default)
			)
			(layer "F.Fab")
		)
		(fp_line
			(start -0.12065 -0.305054)
			(end -0.12065 -0.2794)
			(stroke
				(width 0.1)
				(type default)
			)
			(layer "F.Fab")
		)
		(fp_line
			(start -0.67945 0.3048)
			(end -0.67945 -0.305054)
			(stroke
				(width 0.1)
				(type default)
			)
			(layer "F.Fab")
		)
		(fp_line
			(start -0.67945 -0.305054)
			(end -0.12065 -0.305054)
			(stroke
				(width 0.1)
				(type default)
			)
			(layer "F.Fab")
		)
		(pad "1" smd circle
			(at -0.40005 0 180)
			(size 0 0)
			(layers "F.Cu" "F.Mask" "F.Paste")
			(net "P3V3_AUX")
		)
		(pad "2" smd circle
			(at 0.40005 0 180)
			(size 0 0)
			(layers "F.Cu" "F.Mask" "F.Paste")
			(net "CK440Q_OE_3")
		)
	)
)
